(kicad_pcb
	(version 20240108)
	(generator "pcbnew")
	(generator_version "8.0")
	(general
		(thickness 1.62)
		(legacy_teardrops no)
	)
	(paper "A4")
	(title_block
		(title "Jetson Orin Baseboard")
		(date "2025-03-12")
		(rev "1.3.4")
		(company "Antmicro Ltd")
		(comment 1 "www.antmicro.com")
		(comment 9 "footprints 296-300 of 677")
	)
	(layers
		(0 "F.Cu" signal)
		(1 "In1.Cu" signal)
		(2 "In2.Cu" signal)
		(3 "In3.Cu" signal)
		(4 "In4.Cu" jumper)
		(5 "In5.Cu" signal)
		(6 "In6.Cu" signal)
		(31 "B.Cu" signal)
		(32 "B.Adhes" user "B.Adhesive")
		(33 "F.Adhes" user "F.Adhesive")
		(34 "B.Paste" user)
		(35 "F.Paste" user)
		(36 "B.SilkS" user "B.Silkscreen")
		(37 "F.SilkS" user "F.Silkscreen")
		(38 "B.Mask" user)
		(39 "F.Mask" user)
		(40 "Dwgs.User" user "User.Drawings")
		(41 "Cmts.User" user "User.Comments")
		(42 "Eco1.User" user "User.Eco1")
		(43 "Eco2.User" user "User.Eco2")
		(44 "Edge.Cuts" user)
		(45 "Margin" user)
		(46 "B.CrtYd" user "B.Courtyard")
		(47 "F.CrtYd" user "F.Courtyard")
		(48 "B.Fab" user)
		(49 "F.Fab" user)
	)
	(footprint "antmicro-footprints:R_0402_1005Metric"
		(layer "B.Cu")
		(at 59.69 97.15 180)
		(descr "Resistor SMD 0402")
		(tags "resistor SMD 0402")
		(property "Reference" "R262"
			(at -1.34 0.53 0)
			(layer "B.SilkS")
			(effects
				(font
					(size 0.7 0.7)
					(thickness 0.15)
				)
				(justify left bottom mirror)
			)
		)
		(property "Value" "R_4k7_0402"
			(at 0 -1.4 0)
			(layer "B.Fab")
			(effects
				(font
					(size 0.7 0.7)
					(thickness 0.15)
				)
				(justify left bottom mirror)
			)
		)
		(property "Footprint" "antmicro-footprints:R_0402_1005Metric"
			(at 0 0 180)
			(layer "F.Fab")
			(hide yes)
			(effects
				(font
					(size 1.27 1.27)
					(thickness 0.15)
				)
			)
		)
		(property "Datasheet" "https://www.bourns.com/docs/product-datasheets/cr.pdf"
			(at 0 0 180)
			(layer "F.Fab")
			(hide yes)
			(effects
				(font
					(size 1.27 1.27)
					(thickness 0.15)
				)
			)
		)
		(property "Author" "Antmicro"
			(at 119.38 194.3 0)
			(layer "B.Fab")
			(hide yes)
			(effects
				(font
					(size 1 1)
					(thickness 0.15)
				)
				(justify mirror)
			)
		)
		(property "License" "Apache-2.0"
			(at 119.38 194.3 0)
			(layer "B.Fab")
			(hide yes)
			(effects
				(font
					(size 1 1)
					(thickness 0.15)
				)
				(justify mirror)
			)
		)
		(property "MPN" "CR0402-FX-4701GLF"
			(at 119.38 194.3 0)
			(layer "B.Fab")
			(hide yes)
			(effects
				(font
					(size 1 1)
					(thickness 0.15)
				)
				(justify mirror)
			)
		)
		(property "Manufacturer" "Bourns"
			(at 119.38 194.3 0)
			(layer "B.Fab")
			(hide yes)
			(effects
				(font
					(size 1 1)
					(thickness 0.15)
				)
				(justify mirror)
			)
		)
		(property "Tolerance" "1%"
			(at 119.38 194.3 0)
			(layer "B.Fab")
			(hide yes)
			(effects
				(font
					(size 1 1)
					(thickness 0.15)
				)
				(justify mirror)
			)
		)
		(property "Val" "4k7"
			(at 119.38 194.3 0)
			(layer "B.Fab")
			(hide yes)
			(effects
				(font
					(size 1 1)
					(thickness 0.15)
				)
				(justify mirror)
			)
		)
		(sheetname "USB Debug, DP")
		(sheetfile "usb.kicad_sch")
		(attr smd)
		(fp_rect
			(start -0.925 0.47)
			(end 0.925 -0.47)
			(stroke
				(width 0.05)
				(type default)
			)
			(fill none)
			(layer "B.CrtYd")
		)
		(fp_rect
			(start -0.5 0.25)
			(end 0.5 -0.25)
			(stroke
				(width 0.15)
				(type solid)
			)
			(fill none)
			(layer "B.Fab")
		)
		(fp_text user "Author: Antmicro"
			(at -0.95 -4.169 0)
			(layer "B.Fab")
			(hide yes)
			(effects
				(font
					(size 0.7 0.7)
					(thickness 0.15)
				)
				(justify left bottom mirror)
			)
		)
		(fp_text user "License: Apache-2.0"
			(at -0.95 -5.169 0)
			(layer "B.Fab")
			(hide yes)
			(effects
				(font
					(size 0.7 0.7)
					(thickness 0.15)
				)
				(justify left bottom mirror)
			)
		)
		(fp_text user "${REFERENCE}"
			(at -0.95 -3.168 0)
			(layer "B.Fab")
			(hide yes)
			(effects
				(font
					(size 0.7 0.7)
					(thickness 0.15)
				)
				(justify left bottom mirror)
			)
		)
		(pad "1" smd roundrect
			(at -0.48 0 180)
			(size 0.59 0.64)
			(layers "B.Cu" "B.Paste" "B.Mask")
			(roundrect_rratio 0.25)
			(net 87 "+3V3")
			(pintype "passive")
		)
		(pad "2" smd roundrect
			(at 0.48 0 180)
			(size 0.59 0.64)
			(layers "B.Cu" "B.Paste" "B.Mask")
			(roundrect_rratio 0.25)
			(net 302 "/USB Debug, DP/PDC_I2C1_SCL")
			(pintype "passive")
		)
	)
	(footprint "antmicro-footprints:C_2220_5650Metric"
		(layer "B.Cu")
		(at 33.8 89.6 180)
		(descr "Capacitor SMD 2220")
		(tags "capacitor SMD 2220")
		(property "Reference" "C82"
			(at -4.49 -0.28 90)
			(layer "B.SilkS")
			(effects
				(font
					(size 0.7 0.7)
					(thickness 0.15)
				)
				(justify left bottom mirror)
			)
		)
		(property "Value" "C_22u_100V_2220"
			(at 0 -3.9 0)
			(layer "B.Fab")
			(effects
				(font
					(size 0.7 0.7)
					(thickness 0.15)
				)
				(justify left bottom mirror)
			)
		)
		(property "Footprint" "antmicro-footprints:C_2220_5650Metric"
			(at 0 0 180)
			(layer "F.Fab")
			(hide yes)
			(effects
				(font
					(size 1.27 1.27)
					(thickness 0.15)
				)
			)
		)
		(property "Datasheet" "https://product.tdk.com/en/search/capacitor/ceramic/mlcc/info?part_no=C5750X7S2A226M280KB"
			(at 0 0 180)
			(layer "F.Fab")
			(hide yes)
			(effects
				(font
					(size 1.27 1.27)
					(thickness 0.15)
				)
			)
		)
		(property "Author" "Antmicro"
			(at 67.6 179.2 0)
			(layer "B.Fab")
			(hide yes)
			(effects
				(font
					(size 1 1)
					(thickness 0.15)
				)
				(justify mirror)
			)
		)
		(property "Dielectric" "X7S"
			(at 67.6 179.2 0)
			(layer "B.Fab")
			(hide yes)
			(effects
				(font
					(size 1 1)
					(thickness 0.15)
				)
				(justify mirror)
			)
		)
		(property "License" "Apache-2.0"
			(at 67.6 179.2 0)
			(layer "B.Fab")
			(hide yes)
			(effects
				(font
					(size 1 1)
					(thickness 0.15)
				)
				(justify mirror)
			)
		)
		(property "MPN" "C5750X7S2A226M280KB"
			(at 67.6 179.2 0)
			(layer "B.Fab")
			(hide yes)
			(effects
				(font
					(size 1 1)
					(thickness 0.15)
				)
				(justify mirror)
			)
		)
		(property "Manufacturer" "TDK"
			(at 67.6 179.2 0)
			(layer "B.Fab")
			(hide yes)
			(effects
				(font
					(size 1 1)
					(thickness 0.15)
				)
				(justify mirror)
			)
		)
		(property "Public" "False"
			(at 67.6 179.2 0)
			(layer "B.Fab")
			(hide yes)
			(effects
				(font
					(size 1 1)
					(thickness 0.15)
				)
				(justify mirror)
			)
		)
		(property "Val" "22u"
			(at 67.6 179.2 0)
			(layer "B.Fab")
			(hide yes)
			(effects
				(font
					(size 1 1)
					(thickness 0.15)
				)
				(justify mirror)
			)
		)
		(property "Voltage" "100V"
			(at 67.6 179.2 0)
			(layer "B.Fab")
			(hide yes)
			(effects
				(font
					(size 1 1)
					(thickness 0.15)
				)
				(justify mirror)
			)
		)
		(sheetname "Ethernet")
		(sheetfile "ethernet.kicad_sch")
		(attr smd)
		(fp_line
			(start 1.415 2.61)
			(end -1.415 2.61)
			(stroke
				(width 0.15)
				(type solid)
			)
			(layer "B.SilkS")
		)
		(fp_line
			(start 1.415 -2.61)
			(end -1.415 -2.61)
			(stroke
				(width 0.15)
				(type solid)
			)
			(layer "B.SilkS")
		)
		(fp_rect
			(start -3.7 2.95)
			(end 3.7 -2.95)
			(stroke
				(width 0.05)
				(type solid)
			)
			(fill none)
			(layer "B.CrtYd")
		)
		(fp_rect
			(start -2.85 2.5)
			(end 2.85 -2.5)
			(stroke
				(width 0.15)
				(type solid)
			)
			(fill none)
			(layer "B.Fab")
		)
		(fp_text user "Author: Antmicro"
			(at -3.7 -7.9 0)
			(layer "B.Fab")
			(hide yes)
			(effects
				(font
					(size 0.7 0.7)
					(thickness 0.15)
				)
				(justify left bottom mirror)
			)
		)
		(fp_text user "License: Apache-2.0"
			(at -3.7 -6.9 0)
			(layer "B.Fab")
			(hide yes)
			(effects
				(font
					(size 0.7 0.7)
					(thickness 0.15)
				)
				(justify left bottom mirror)
			)
		)
		(fp_text user "${REFERENCE}"
			(at -3.7 -5.9 0)
			(layer "B.Fab")
			(hide yes)
			(effects
				(font
					(size 0.7 0.7)
					(thickness 0.15)
				)
				(justify left bottom mirror)
			)
		)
		(pad "1" smd roundrect
			(at -2.55 0 180)
			(size 1.8 5.4)
			(layers "B.Cu" "B.Paste" "B.Mask")
			(roundrect_rratio 0.138889)
			(net 106 "GNDD")
			(pintype "passive")
		)
		(pad "2" smd roundrect
			(at 2.55 0 180)
			(size 1.8 5.4)
			(layers "B.Cu" "B.Paste" "B.Mask")
			(roundrect_rratio 0.138889)
			(net 105 "/Ethernet/VDD")
			(pintype "passive")
		)
	)
	(footprint "antmicro-footprints:Fiducial_1mm_Mask2mm"
		(layer "B.Cu")
		(at 39.3 81.5 180)
		(descr "Circular Fiducial, 1mm bare copper, 3mm soldermask opening")
		(tags "fiducial")
		(property "Reference" "FID6"
			(at 0 1.4 0)
			(layer "B.SilkS")
			(hide yes)
			(effects
				(font
					(size 0.7 0.7)
					(thickness 0.15)
				)
				(justify left bottom mirror)
			)
		)
		(property "Value" "Fiducial_1mm_Mask2mm"
			(at 0 -2.2 0)
			(layer "B.Fab")
			(effects
				(font
					(size 0.7 0.7)
					(thickness 0.15)
				)
				(justify left bottom mirror)
			)
		)
		(property "Footprint" "antmicro-footprints:Fiducial_1mm_Mask2mm"
			(at 0 0 180)
			(layer "F.Fab")
			(hide yes)
			(effects
				(font
					(size 1.27 1.27)
					(thickness 0.15)
				)
			)
		)
		(attr board_only exclude_from_pos_files exclude_from_bom)
		(fp_circle
			(center 0 0)
			(end 1.24 0)
			(stroke
				(width 0.05)
				(type solid)
			)
			(fill none)
			(layer "B.CrtYd")
		)
		(fp_circle
			(center 0 0)
			(end 0.999 0)
			(stroke
				(width 0.15)
				(type solid)
			)
			(fill none)
			(layer "B.Fab")
		)
		(fp_text user "License: Apache-2.0"
			(at -1.25 -7.003 0)
			(layer "B.Fab")
			(hide yes)
			(effects
				(font
					(size 0.7 0.7)
					(thickness 0.15)
				)
				(justify left bottom mirror)
			)
		)
		(fp_text user "${REFERENCE}"
			(at -1.25 -4.603 0)
			(layer "B.Fab")
			(hide yes)
			(effects
				(font
					(size 0.7 0.7)
					(thickness 0.15)
				)
				(justify left bottom mirror)
			)
		)
		(fp_text user "Author: Antmicro"
			(at -1.25 -5.803 0)
			(layer "B.Fab")
			(hide yes)
			(effects
				(font
					(size 0.7 0.7)
					(thickness 0.15)
				)
				(justify left bottom mirror)
			)
		)
		(pad "" smd circle
			(at 0 0 180)
			(size 1 1)
			(layers "B.Cu" "B.Mask")
			(solder_mask_margin 0.5)
			(clearance 0.5)
		)
	)
	(footprint "antmicro-footprints:SOT-23-3"
		(layer "B.Cu")
		(at 42.8 77.975 180)
		(property "Reference" "Q16"
			(at -0.22 -2.66 180)
			(layer "B.SilkS")
			(effects
				(font
					(size 0.7 0.7)
					(thickness 0.15)
				)
				(justify left bottom mirror)
			)
		)
		(property "Value" "SSM3J332R"
			(at -1.9 -2.7 0)
			(layer "B.Fab")
			(effects
				(font
					(size 0.7 0.7)
					(thickness 0.15)
				)
				(justify left bottom mirror)
			)
		)
		(property "Footprint" "antmicro-footprints:SOT-23-3"
			(at 0 0 180)
			(layer "F.Fab")
			(hide yes)
			(effects
				(font
					(size 1.27 1.27)
					(thickness 0.15)
				)
			)
		)
		(property "Datasheet" "https://www.mouser.com/datasheet/2/408/SSM3J332R_datasheet_en_20181015-1150575.pdf"
			(at 0 0 180)
			(layer "F.Fab")
			(hide yes)
			(effects
				(font
					(size 1.27 1.27)
					(thickness 0.15)
				)
			)
		)
		(property "Author" "Antmicro"
			(at 87.4 156.2 0)
			(layer "B.Fab")
			(hide yes)
			(effects
				(font
					(size 1 1)
					(thickness 0.15)
				)
				(justify mirror)
			)
		)
		(property "License" "Apache-2.0"
			(at 87.4 156.2 0)
			(layer "B.Fab")
			(hide yes)
			(effects
				(font
					(size 1 1)
					(thickness 0.15)
				)
				(justify mirror)
			)
		)
		(property "MPN" "SSM3J332R,LF"
			(at 87.4 156.2 0)
			(layer "B.Fab")
			(hide yes)
			(effects
				(font
					(size 1 1)
					(thickness 0.15)
				)
				(justify mirror)
			)
		)
		(property "Manufacturer" "Toshiba"
			(at 87.4 156.2 0)
			(layer "B.Fab")
			(hide yes)
			(effects
				(font
					(size 1 1)
					(thickness 0.15)
				)
				(justify mirror)
			)
		)
		(sheetname "Supply")
		(sheetfile "supply.kicad_sch")
		(attr smd)
		(fp_line
			(start 0.7 1.5)
			(end 0.7 0.4)
			(stroke
				(width 0.15)
				(type solid)
			)
			(layer "B.SilkS")
		)
		(fp_line
			(start 0.7 -1.5)
			(end 0.7 -0.4)
			(stroke
				(width 0.15)
				(type solid)
			)
			(layer "B.SilkS")
		)
		(fp_line
			(start -0.7 1.5)
			(end 0.7 1.5)
			(stroke
				(width 0.15)
				(type solid)
			)
			(layer "B.SilkS")
		)
		(fp_line
			(start -0.7 1.5)
			(end -0.85 1.35)
			(stroke
				(width 0.15)
				(type solid)
			)
			(layer "B.SilkS")
		)
		(fp_line
			(start -0.7 -1.35)
			(end -0.7 -1.5)
			(stroke
				(width 0.15)
				(type solid)
			)
			(layer "B.SilkS")
		)
		(fp_line
			(start -0.7 -1.5)
			(end 0.7 -1.5)
			(stroke
				(width 0.15)
				(type solid)
			)
			(layer "B.SilkS")
		)
		(fp_line
			(start -0.85 1.35)
			(end -1.45 1.35)
			(stroke
				(width 0.15)
				(type solid)
			)
			(layer "B.SilkS")
		)
		(fp_line
			(start 1.75 0.45)
			(end 0.825 0.45)
			(stroke
				(width 0.05)
				(type solid)
			)
			(layer "B.CrtYd")
		)
		(fp_line
			(start 1.75 -0.45)
			(end 1.75 0.45)
			(stroke
				(width 0.05)
				(type solid)
			)
			(layer "B.CrtYd")
		)
		(fp_line
			(start 0.85 -0.45)
			(end 1.75 -0.45)
			(stroke
				(width 0.05)
				(type solid)
			)
			(layer "B.CrtYd")
		)
		(fp_line
			(start 0.85 -1.65)
			(end 0.85 -0.45)
			(stroke
				(width 0.05)
				(type solid)
			)
			(layer "B.CrtYd")
		)
		(fp_line
			(start 0.825 1.6)
			(end -0.9 1.6)
			(stroke
				(width 0.05)
				(type solid)
			)
			(layer "B.CrtYd")
		)
		(fp_line
			(start 0.825 0.45)
			(end 0.825 1.6)
			(stroke
				(width 0.05)
				(type solid)
			)
			(layer "B.CrtYd")
		)
		(fp_line
			(start -0.85 0.5)
			(end -0.85 -0.5)
			(stroke
				(width 0.05)
				(type solid)
			)
			(layer "B.CrtYd")
		)
		(fp_line
			(start -0.85 -0.5)
			(end -1.75 -0.5)
			(stroke
				(width 0.05)
				(type solid)
			)
			(layer "B.CrtYd")
		)
		(fp_line
			(start -0.85 -1.4)
			(end -0.85 -1.65)
			(stroke
				(width 0.05)
				(type solid)
			)
			(layer "B.CrtYd")
		)
		(fp_line
			(start -0.85 -1.65)
			(end 0.85 -1.65)
			(stroke
				(width 0.05)
				(type solid)
			)
			(layer "B.CrtYd")
		)
		(fp_line
			(start -0.9 1.4)
			(end -0.9 1.6)
			(stroke
				(width 0.05)
				(type solid)
			)
			(layer "B.CrtYd")
		)
		(fp_line
			(start -1.75 1.4)
			(end -0.9 1.4)
			(stroke
				(width 0.05)
				(type solid)
			)
			(layer "B.CrtYd")
		)
		(fp_line
			(start -1.75 1.4)
			(end -1.75 0.5)
			(stroke
				(width 0.05)
				(type solid)
			)
			(layer "B.CrtYd")
		)
		(fp_line
			(start -1.75 0.5)
			(end -0.85 0.5)
			(stroke
				(width 0.05)
				(type solid)
			)
			(layer "B.CrtYd")
		)
		(fp_line
			(start -1.75 -0.5)
			(end -1.75 -1.4)
			(stroke
				(width 0.05)
				(type solid)
			)
			(layer "B.CrtYd")
		)
		(fp_line
			(start -1.75 -1.4)
			(end -0.85 -1.4)
			(stroke
				(width 0.05)
				(type solid)
			)
			(layer "B.CrtYd")
		)
		(fp_line
			(start 0.688 1.526)
			(end -0.437 1.526)
			(stroke
				(width 0.15)
				(type solid)
			)
			(layer "B.Fab")
		)
		(fp_line
			(start 0.688 1.52)
			(end 0.688 -1.519)
			(stroke
				(width 0.15)
				(type solid)
			)
			(layer "B.Fab")
		)
		(fp_line
			(start 0.688 -1.519)
			(end -0.712 -1.519)
			(stroke
				(width 0.15)
				(type solid)
			)
			(layer "B.Fab")
		)
		(fp_line
			(start -0.712 1.325)
			(end -0.437 1.526)
			(stroke
				(width 0.15)
				(type solid)
			)
			(layer "B.Fab")
		)
		(fp_line
			(start -0.712 -1.523)
			(end -0.712 1.325)
			(stroke
				(width 0.15)
				(type solid)
			)
			(layer "B.Fab")
		)
		(fp_text user "License: Apache-2.0"
			(at -1.8 -6.8 0)
			(layer "B.Fab")
			(hide yes)
			(effects
				(font
					(size 0.7 0.7)
					(thickness 0.15)
				)
				(justify left bottom mirror)
			)
		)
		(fp_text user "Author: Antmicro"
			(at -1.837 -5.3 0)
			(layer "B.Fab")
			(hide yes)
			(effects
				(font
					(size 0.7 0.7)
					(thickness 0.15)
				)
				(justify left bottom mirror)
			)
		)
		(fp_text user "${REFERENCE}"
			(at -1.837 -4 0)
			(layer "B.Fab")
			(hide yes)
			(effects
				(font
					(size 0.7 0.7)
					(thickness 0.15)
				)
				(justify left bottom mirror)
			)
		)
		(pad "1" smd roundrect
			(at -1.1 0.951 180)
			(size 1 0.6)
			(layers "B.Cu" "B.Paste" "B.Mask")
			(roundrect_rratio 0.15)
			(net 631 "Net-(Q16-G)")
			(pinfunction "G")
			(pintype "bidirectional")
		)
		(pad "2" smd roundrect
			(at -1.1 -0.949 180)
			(size 1 0.6)
			(layers "B.Cu" "B.Paste" "B.Mask")
			(roundrect_rratio 0.15)
			(net 328 "/Supply/VCC_IN")
			(pinfunction "S")
			(pintype "bidirectional")
		)
		(pad "3" smd roundrect
			(at 1.1 0.0005 180)
			(size 1 0.6)
			(layers "B.Cu" "B.Paste" "B.Mask")
			(roundrect_rratio 0.15)
			(net 500 "POE_OUTPUT")
			(pinfunction "D")
			(pintype "bidirectional")
		)
	)
	(footprint "antmicro-footprints:TP_SMD_0.75mm"
		(layer "B.Cu")
		(at 77.69 75.395)
		(property "Reference" "TP3"
			(at 2.485 0.445 0)
			(layer "B.SilkS")
			(effects
				(font
					(size 0.7 0.7)
					(thickness 0.15)
				)
				(justify left bottom mirror)
			)
		)
		(property "Value" "TP_0.75mm_SMD"
			(at 0 -1.2 180)
			(layer "B.Fab")
			(effects
				(font
					(size 0.7 0.7)
					(thickness 0.15)
				)
				(justify left bottom mirror)
			)
		)
		(property "Footprint" "antmicro-footprints:TP_SMD_0.75mm"
			(at 0 0 0)
			(layer "F.Fab")
			(hide yes)
			(effects
				(font
					(size 1.27 1.27)
					(thickness 0.15)
				)
			)
		)
		(property "Author" "Antmicro"
			(at 0 0 0)
			(layer "B.Fab")
			(hide yes)
			(effects
				(font
					(size 1 1)
					(thickness 0.15)
				)
				(justify mirror)
			)
		)
		(property "License" "Apache-2.0"
			(at 0 0 0)
			(layer "B.Fab")
			(hide yes)
			(effects
				(font
					(size 1 1)
					(thickness 0.15)
				)
				(justify mirror)
			)
		)
		(property "MPN" ""
			(at 0 0 0)
			(layer "B.Fab")
			(hide yes)
			(effects
				(font
					(size 1 1)
					(thickness 0.15)
				)
				(justify mirror)
			)
		)
		(property "Manufacturer" ""
			(at 0 0 0)
			(layer "B.Fab")
			(hide yes)
			(effects
				(font
					(size 1 1)
					(thickness 0.15)
				)
				(justify mirror)
			)
		)
		(sheetname "SoM")
		(sheetfile "som.kicad_sch")
		(attr exclude_from_pos_files exclude_from_bom)
		(fp_circle
			(center 0 0)
			(end 0.475 0)
			(stroke
				(width 0.05)
				(type default)
			)
			(fill none)
			(layer "B.CrtYd")
		)
		(fp_text user "License: Apache-2.0"
			(at -0.4 -5.101 180)
			(layer "B.Fab")
			(hide yes)
			(effects
				(font
					(size 0.7 0.7)
					(thickness 0.15)
				)
				(justify left bottom mirror)
			)
		)
		(fp_text user "Author: Antmicro"
			(at -0.4 -3.901 180)
			(layer "B.Fab")
			(hide yes)
			(effects
				(font
					(size 0.7 0.7)
					(thickness 0.15)
				)
				(justify left bottom mirror)
			)
		)
		(fp_text user "${REFERENCE}"
			(at -0.4 -2.7 180)
			(layer "B.Fab")
			(hide yes)
			(effects
				(font
					(size 0.7 0.7)
					(thickness 0.15)
				)
				(justify left bottom mirror)
			)
		)
		(pad "1" smd circle
			(at 0 0)
			(size 0.75 0.75)
			(layers "B.Cu" "B.Mask")
			(net 452 "/SoM/~{MOD_SLEEP}")
			(pinfunction "1")
			(pintype "passive")
		)
	)
)
